# SCM (Grand Teton) — schematic netlist excerpt (pin names and nets, part order shuffled) for the footprints in the layout excerpt that follows; sources: Cadence DE-HDL packaged netlist, KiCad conversion of 12092022_DA0F0TMDCD0_F0T_Management_Board_D_brd_V3_OCP.brd

R456  Q_RES  0 5% CHIP  pkg 0402LF  page 35 : A = SMB_BMC_ALERT9_N ; B = SMB_BMC_ALERT9_R1_N
R773  Q_RES  33.2 1% CHIP  pkg 0402LF  page 35 : A = FM_SLPS3_GF_N ; B = FM_SLPS3_GF_R_N

(kicad_pcb
	(version 20260206)
	(generator "pcbnew")
	(generator_version "10.0")
	(general
		(thickness 1.6)
		(legacy_teardrops no)
	)
	(paper "A4")
	(title_block
		(title "12092022_DA0F0TMDCD0_F0T_Management_Board_D_brd_V3_OCP.brd")
		(comment 1 "Grand Teton / footprints 1374-1375 of 1440")
	)
	(layers
		(0 "F.Cu" signal "TOP")
		(4 "In1.Cu" signal "GND")
		(6 "In2.Cu" signal "IN1")
		(8 "In3.Cu" signal "GND1")
		(10 "In4.Cu" signal "IN2")
		(12 "In5.Cu" signal "VCC")
		(14 "In6.Cu" signal "VCC1")
		(16 "In7.Cu" signal "IN3")
		(18 "In8.Cu" signal "GND2")
		(20 "In9.Cu" signal "IN4")
		(22 "In10.Cu" signal "GND3")
		(2 "B.Cu" signal "BOTTOM")
		(9 "F.Adhes" user "F.Adhesive")
		(11 "B.Adhes" user "B.Adhesive")
		(13 "F.Paste" user "Package Geometry/Pastemask Top")
		(15 "B.Paste" user "Package Geometry/Pastemask Bottom")
		(5 "F.SilkS" user "Ref Des/Silkscreen Top")
		(7 "B.SilkS" user "Ref Des/Silkscreen Bottom")
		(1 "F.Mask" user "Board Geometry/Soldermask Top")
		(3 "B.Mask" user "Board Geometry/Soldermask Bottom")
		(17 "Dwgs.User" user "User.Drawings")
		(19 "Cmts.User" user "User.Comments")
		(21 "Eco1.User" user "User.Eco1")
		(23 "Eco2.User" user "User.Eco2")
		(25 "Edge.Cuts" user "Board Geometry/Outline")
		(27 "Margin" user)
		(31 "F.CrtYd" user "Package Geometry/Place Bound Top")
		(29 "B.CrtYd" user "Package Geometry/Place Bound Bottom")
		(35 "F.Fab" user "Ref Des/Assembly Top")
		(33 "B.Fab" user "Ref Des/Assembly Bottom")
	)
	(footprint ""
		(layer "B.Cu")
		(at 29.4894 -93.1164)
		(property "Reference" "R773"
			(at 0 0 0)
			(layer "B.SilkS")
			(hide yes)
			(effects
				(font
					(size 1.27 1.27)
				)
				(justify mirror)
			)
		)
		(property "Value" ""
			(at 0 0 0)
			(layer "B.Fab")
			(effects
				(font
					(size 1.27 1.27)
				)
				(justify mirror)
			)
		)
		(duplicate_pad_numbers_are_jumpers no)
		(fp_line
			(start -0.7874 -0.4064)
			(end -0.7874 0.4064)
			(stroke
				(width 0.1524)
				(type default)
			)
			(layer "B.SilkS")
		)
		(fp_line
			(start -0.7874 0.4064)
			(end 0.7874 0.4064)
			(stroke
				(width 0.1524)
				(type default)
			)
			(layer "B.SilkS")
		)
		(fp_line
			(start 0.7874 -0.4064)
			(end -0.7874 -0.4064)
			(stroke
				(width 0.1524)
				(type default)
			)
			(layer "B.SilkS")
		)
		(fp_line
			(start 0.7874 0.4064)
			(end 0.7874 -0.4064)
			(stroke
				(width 0.1524)
				(type default)
			)
			(layer "B.SilkS")
		)
		(fp_line
			(start -0.67945 -0.3048)
			(end -0.67945 0.3048)
			(stroke
				(width 0.1)
				(type default)
			)
			(layer "B.Fab")
		)
		(fp_line
			(start -0.67945 0.3048)
			(end -0.120396 0.3048)
			(stroke
				(width 0.1)
				(type default)
			)
			(layer "B.Fab")
		)
		(fp_line
			(start -0.12065 -0.3048)
			(end -0.67945 -0.3048)
			(stroke
				(width 0.1)
				(type default)
			)
			(layer "B.Fab")
		)
		(fp_line
			(start -0.12065 -0.2794)
			(end -0.12065 -0.3048)
			(stroke
				(width 0.1)
				(type default)
			)
			(layer "B.Fab")
		)
		(fp_line
			(start -0.120396 0.2794)
			(end 0.12065 0.2794)
			(stroke
				(width 0.1)
				(type default)
			)
			(layer "B.Fab")
		)
		(fp_line
			(start -0.120396 0.3048)
			(end -0.120396 0.2794)
			(stroke
				(width 0.1)
				(type default)
			)
			(layer "B.Fab")
		)
		(fp_line
			(start 0.12065 -0.305054)
			(end 0.12065 -0.2794)
			(stroke
				(width 0.1)
				(type default)
			)
			(layer "B.Fab")
		)
		(fp_line
			(start 0.12065 -0.2794)
			(end -0.12065 -0.2794)
			(stroke
				(width 0.1)
				(type default)
			)
			(layer "B.Fab")
		)
		(fp_line
			(start 0.12065 0.2794)
			(end 0.12065 0.3048)
			(stroke
				(width 0.1)
				(type default)
			)
			(layer "B.Fab")
		)
		(fp_line
			(start 0.12065 0.3048)
			(end 0.67945 0.3048)
			(stroke
				(width 0.1)
				(type default)
			)
			(layer "B.Fab")
		)
		(fp_line
			(start 0.67945 -0.305054)
			(end 0.12065 -0.305054)
			(stroke
				(width 0.1)
				(type default)
			)
			(layer "B.Fab")
		)
		(fp_line
			(start 0.67945 0.3048)
			(end 0.67945 -0.305054)
			(stroke
				(width 0.1)
				(type default)
			)
			(layer "B.Fab")
		)
		(pad "1" smd circle
			(at 0.40005 0 180)
			(size 0 0)
			(layers "B.Cu" "B.Mask" "B.Paste")
			(net "FM_SLPS3_GF_N")
		)
		(pad "2" smd circle
			(at -0.40005 0 180)
			(size 0 0)
			(layers "B.Cu" "B.Mask" "B.Paste")
			(net "FM_SLPS3_GF_R_N")
		)
	)
	(footprint ""
		(layer "B.Cu")
		(at 12.319 -87.376 180)
		(property "Reference" "R456"
			(at 0 0 0)
			(layer "B.SilkS")
			(hide yes)
			(effects
				(font
					(size 1.27 1.27)
				)
				(justify mirror)
			)
		)
		(property "Value" ""
			(at 0 0 0)
			(layer "B.Fab")
			(effects
				(font
					(size 1.27 1.27)
				)
				(justify mirror)
			)
		)
		(duplicate_pad_numbers_are_jumpers no)
		(fp_line
			(start 0.7874 0.4064)
			(end 0.7874 -0.4064)
			(stroke
				(width 0.1524)
				(type default)
			)
			(layer "B.SilkS")
		)
		(fp_line
			(start 0.7874 -0.4064)
			(end -0.7874 -0.4064)
			(stroke
				(width 0.1524)
				(type default)
			)
			(layer "B.SilkS")
		)
		(fp_line
			(start -0.7874 0.4064)
			(end 0.7874 0.4064)
			(stroke
				(width 0.1524)
				(type default)
			)
			(layer "B.SilkS")
		)
		(fp_line
			(start -0.7874 -0.4064)
			(end -0.7874 0.4064)
			(stroke
				(width 0.1524)
				(type default)
			)
			(layer "B.SilkS")
		)
		(fp_line
			(start 0.67945 0.3048)
			(end 0.67945 -0.305054)
			(stroke
				(width 0.1)
				(type default)
			)
			(layer "B.Fab")
		)
		(fp_line
			(start 0.67945 -0.305054)
			(end 0.12065 -0.305054)
			(stroke
				(width 0.1)
				(type default)
			)
			(layer "B.Fab")
		)
		(fp_line
			(start 0.12065 0.3048)
			(end 0.67945 0.3048)
			(stroke
				(width 0.1)
				(type default)
			)
			(layer "B.Fab")
		)
		(fp_line
			(start 0.12065 0.2794)
			(end 0.12065 0.3048)
			(stroke
				(width 0.1)
				(type default)
			)
			(layer "B.Fab")
		)
		(fp_line
			(start 0.12065 -0.2794)
			(end -0.12065 -0.2794)
			(stroke
				(width 0.1)
				(type default)
			)
			(layer "B.Fab")
		)
		(fp_line
			(start 0.12065 -0.305054)
			(end 0.12065 -0.2794)
			(stroke
				(width 0.1)
				(type default)
			)
			(layer "B.Fab")
		)
		(fp_line
			(start -0.120396 0.3048)
			(end -0.120396 0.2794)
			(stroke
				(width 0.1)
				(type default)
			)
			(layer "B.Fab")
		)
		(fp_line
			(start -0.120396 0.2794)
			(end 0.12065 0.2794)
			(stroke
				(width 0.1)
				(type default)
			)
			(layer "B.Fab")
		)
		(fp_line
			(start -0.12065 -0.2794)
			(end -0.12065 -0.3048)
			(stroke
				(width 0.1)
				(type default)
			)
			(layer "B.Fab")
		)
		(fp_line
			(start -0.12065 -0.3048)
			(end -0.67945 -0.3048)
			(stroke
				(width 0.1)
				(type default)
			)
			(layer "B.Fab")
		)
		(fp_line
			(start -0.67945 0.3048)
			(end -0.120396 0.3048)
			(stroke
				(width 0.1)
				(type default)
			)
			(layer "B.Fab")
		)
		(fp_line
			(start -0.67945 -0.3048)
			(end -0.67945 0.3048)
			(stroke
				(width 0.1)
				(type default)
			)
			(layer "B.Fab")
		)
		(pad "1" smd circle
			(at 0.40005 0)
			(size 0 0)
			(layers "B.Cu" "B.Mask" "B.Paste")
			(net "SMB_BMC_ALERT9_N")
		)
		(pad "2" smd circle
			(at -0.40005 0)
			(size 0 0)
			(layers "B.Cu" "B.Mask" "B.Paste")
			(net "SMB_BMC_ALERT9_R1_N")
		)
	)
)
